(kicad_pcb
	(version 20260206)
	(generator "pcbnew")
	(generator_version "10.0")
	(general
		(thickness 1.6)
		(legacy_teardrops no)
	)
	(paper "A4")
	(title_block
		(title "timecard-production-celestica-r4006 — R4006-B0001-02_R01.brd")
		(comment 1 "Time Appliance Project (Time Card) / footprints 738-742 of 1113")
	)
	(layers
		(0 "F.Cu" signal "TOP")
		(4 "In1.Cu" signal "L02_GND1")
		(6 "In2.Cu" signal "L03_SIG1")
		(8 "In3.Cu" signal "L04_GND2")
		(10 "In4.Cu" signal "L05_VCC1")
		(12 "In5.Cu" signal "L06_VCC2")
		(14 "In6.Cu" signal "L07_GND3")
		(16 "In7.Cu" signal "L08_SIG2")
		(18 "In8.Cu" signal "L09_GND4")
		(2 "B.Cu" signal "BOTTOM")
		(9 "F.Adhes" user "F.Adhesive")
		(11 "B.Adhes" user "B.Adhesive")
		(13 "F.Paste" user "Package Geometry/Pastemask Top")
		(15 "B.Paste" user "Package Geometry/Pastemask Bottom")
		(5 "F.SilkS" user "Ref Des/Silkscreen Top")
		(7 "B.SilkS" user "Ref Des/Silkscreen Bottom")
		(1 "F.Mask" user "Board Geometry/Soldermask Top")
		(3 "B.Mask" user "Board Geometry/Soldermask Bottom")
		(17 "Dwgs.User" user "User.Drawings")
		(19 "Cmts.User" user "User.Comments")
		(21 "Eco1.User" user "User.Eco1")
		(23 "Eco2.User" user "User.Eco2")
		(25 "Edge.Cuts" user "Board Geometry/Outline")
		(27 "Margin" user)
		(31 "F.CrtYd" user "Package Geometry/Place Bound Top")
		(29 "B.CrtYd" user "Package Geometry/Place Bound Bottom")
		(35 "F.Fab" user "Ref Des/Assembly Top")
		(33 "B.Fab" user "Ref Des/Assembly Bottom")
	)
	(footprint ""
		(layer "B.Cu")
		(at 111.125 -100.711 180)
		(property "Reference" "C315"
			(at -0.762 -1.30937 0)
			(unlocked yes)
			(layer "B.SilkS")
			(effects
				(font
					(size 0.7874 0.5842)
					(thickness 0.1524)
				)
				(justify mirror)
			)
		)
		(property "Value" "VAL*"
			(at -0.0762 2.067306 180)
			(unlocked yes)
			(layer "B.Fab")
			(hide yes)
			(effects
				(font
					(size 0.7874 0.5842)
					(thickness 0.1524)
				)
				(justify mirror)
			)
		)
		(property "Tolerance" "TOL*"
			(at -0.0762 3.032506 180)
			(unlocked yes)
			(layer "Cmts.User")
			(hide yes)
			(effects
				(font
					(size 0.7874 0.5842)
					(thickness 0.1524)
				)
				(justify mirror)
			)
		)
		(property "User Part Number" "PARTNUM*"
			(at -0.1016 4.023106 180)
			(unlocked yes)
			(layer "Cmts.User")
			(hide yes)
			(effects
				(font
					(size 0.7874 0.5842)
					(thickness 0.1524)
				)
				(justify mirror)
			)
		)
		(property "Device Type" "CAPACITOR-G105-0B104-EK,0.1UF,A"
			(at -0.0508 1.127506 180)
			(unlocked yes)
			(layer "B.Fab")
			(hide yes)
			(effects
				(font
					(size 0.7874 0.5842)
					(thickness 0.1524)
				)
				(justify mirror)
			)
		)
		(duplicate_pad_numbers_are_jumpers no)
		(fp_line
			(start 1.143 0.5588)
			(end -1.143 0.5588)
			(stroke
				(width 0.1)
				(type default)
			)
			(layer "B.SilkS")
		)
		(fp_line
			(start 1.143 -0.5588)
			(end 1.143 0.5588)
			(stroke
				(width 0.1)
				(type default)
			)
			(layer "B.SilkS")
		)
		(fp_line
			(start -1.143 0.5588)
			(end -1.143 -0.5588)
			(stroke
				(width 0.1)
				(type default)
			)
			(layer "B.SilkS")
		)
		(fp_line
			(start -1.143 -0.5588)
			(end 1.143 -0.5588)
			(stroke
				(width 0.1)
				(type default)
			)
			(layer "B.SilkS")
		)
		(fp_poly
			(pts
				(xy 1.143 0.5588) (xy -1.143 0.5588) (xy -1.143 -0.5588) (xy 1.143 -0.5588)
			)
			(stroke
				(width 0)
				(type default)
			)
			(fill no)
			(layer "B.CrtYd")
		)
		(fp_line
			(start 0.508 0.3048)
			(end -0.508 0.3048)
			(stroke
				(width 0.1)
				(type default)
			)
			(layer "B.Fab")
		)
		(fp_line
			(start 0.508 -0.3048)
			(end 0.508 0.3048)
			(stroke
				(width 0.1)
				(type default)
			)
			(layer "B.Fab")
		)
		(fp_line
			(start -0.508 0.3048)
			(end -0.508 -0.3048)
			(stroke
				(width 0.1)
				(type default)
			)
			(layer "B.Fab")
		)
		(fp_line
			(start -0.508 -0.3048)
			(end 0.508 -0.3048)
			(stroke
				(width 0.1)
				(type default)
			)
			(layer "B.Fab")
		)
		(pad "1" smd rect
			(at 0.5334 0)
			(size 0.7112 0.6096)
			(layers "B.Cu" "B.Mask" "B.Paste")
			(net "XP3R3V_FPGA")
		)
		(pad "2" smd rect
			(at -0.5334 0)
			(size 0.7112 0.6096)
			(layers "B.Cu" "B.Mask" "B.Paste")
			(net "SG")
		)
		(zone
			(layer "B.Cu")
			(hatch none 0.5)
			(connect_pads
				(clearance 0)
			)
			(min_thickness 0.25)
			(keepout
				(tracks not_allowed)
				(vias allowed)
				(pads allowed)
				(copperpour not_allowed)
				(footprints allowed)
			)
			(placement
				(enabled no)
				(sheetname "")
			)
			(fill
				(thermal_gap 0.5)
				(thermal_bridge_width 0.5)
				(island_removal_mode 0)
			)
			(polygon
				(pts
					(xy 111.0488 -101.0158) (xy 111.0488 -100.4062) (xy 111.2012 -100.4062) (xy 111.2012 -101.0158)
				)
			)
		)
		(zone
			(layer "B.Cu")
			(hatch none 0.5)
			(connect_pads
				(clearance 0)
			)
			(min_thickness 0.25)
			(keepout
				(tracks allowed)
				(vias not_allowed)
				(pads allowed)
				(copperpour not_allowed)
				(footprints allowed)
			)
			(placement
				(enabled no)
				(sheetname "")
			)
			(fill
				(thermal_gap 0.5)
				(thermal_bridge_width 0.5)
				(island_removal_mode 0)
			)
			(polygon
				(pts
					(xy 111.0488 -101.0158) (xy 111.0488 -100.4062) (xy 111.2012 -100.4062) (xy 111.2012 -101.0158)
				)
			)
		)
	)
	(footprint ""
		(layer "B.Cu")
		(at 22.7584 -61.5442 -90)
		(property "Reference" "R314"
			(at 3.1242 -0.69723 270)
			(unlocked yes)
			(layer "B.SilkS")
			(effects
				(font
					(size 0.7874 0.5842)
					(thickness 0.1524)
				)
				(justify mirror)
			)
		)
		(property "Value" "VAL*"
			(at -0.02032 2.13233 270)
			(unlocked yes)
			(layer "B.Fab")
			(hide yes)
			(effects
				(font
					(size 0.7874 0.5842)
					(thickness 0.1524)
				)
				(justify mirror)
			)
		)
		(property "Tolerance" "TOL*"
			(at -0.044704 3.05435 270)
			(unlocked yes)
			(layer "Cmts.User")
			(hide yes)
			(effects
				(font
					(size 0.7874 0.5842)
					(thickness 0.1524)
				)
				(justify mirror)
			)
		)
		(property "User Part Number" "PARTNUM*"
			(at -0.02032 4.024884 270)
			(unlocked yes)
			(layer "Cmts.User")
			(hide yes)
			(effects
				(font
					(size 0.7874 0.5842)
					(thickness 0.1524)
				)
				(justify mirror)
			)
		)
		(property "Device Type" "RESISTOR-G155-14701-01,4.7KOHMA"
			(at -0.008382 1.210564 270)
			(unlocked yes)
			(layer "B.Fab")
			(hide yes)
			(effects
				(font
					(size 0.7874 0.5842)
					(thickness 0.1524)
				)
				(justify mirror)
			)
		)
		(duplicate_pad_numbers_are_jumpers no)
		(fp_line
			(start -1.143 0.5588)
			(end -1.143 -0.5588)
			(stroke
				(width 0.1)
				(type default)
			)
			(layer "B.SilkS")
		)
		(fp_line
			(start 1.143 0.5588)
			(end -1.143 0.5588)
			(stroke
				(width 0.1)
				(type default)
			)
			(layer "B.SilkS")
		)
		(fp_line
			(start -1.143 -0.5588)
			(end 1.143 -0.5588)
			(stroke
				(width 0.1)
				(type default)
			)
			(layer "B.SilkS")
		)
		(fp_line
			(start 1.143 -0.5588)
			(end 1.143 0.5588)
			(stroke
				(width 0.1)
				(type default)
			)
			(layer "B.SilkS")
		)
		(fp_poly
			(pts
				(xy 1.143 0.5588) (xy -1.143 0.5588) (xy -1.143 -0.5588) (xy 1.143 -0.5588)
			)
			(stroke
				(width 0)
				(type default)
			)
			(fill no)
			(layer "B.CrtYd")
		)
		(fp_line
			(start -0.508 0.3048)
			(end -0.508 -0.3048)
			(stroke
				(width 0.1)
				(type default)
			)
			(layer "B.Fab")
		)
		(fp_line
			(start 0.508 0.3048)
			(end -0.508 0.3048)
			(stroke
				(width 0.1)
				(type default)
			)
			(layer "B.Fab")
		)
		(fp_line
			(start -0.508 -0.3048)
			(end 0.508 -0.3048)
			(stroke
				(width 0.1)
				(type default)
			)
			(layer "B.Fab")
		)
		(fp_line
			(start 0.508 -0.3048)
			(end 0.508 0.3048)
			(stroke
				(width 0.1)
				(type default)
			)
			(layer "B.Fab")
		)
		(pad "1" smd rect
			(at 0.5334 0 90)
			(size 0.7112 0.6096)
			(layers "B.Cu" "B.Mask" "B.Paste")
			(net "XP3R3V_FPGA")
		)
		(pad "2" smd rect
			(at -0.5334 0 90)
			(size 0.7112 0.6096)
			(layers "B.Cu" "B.Mask" "B.Paste")
			(net "UNNAMED_8_PCA9508DPTSSOP8_I51_E")
		)
		(zone
			(layer "B.Cu")
			(hatch none 0.5)
			(connect_pads
				(clearance 0)
			)
			(min_thickness 0.25)
			(keepout
				(tracks not_allowed)
				(vias allowed)
				(pads allowed)
				(copperpour not_allowed)
				(footprints allowed)
			)
			(placement
				(enabled no)
				(sheetname "")
			)
			(fill
				(thermal_gap 0.5)
				(thermal_bridge_width 0.5)
				(island_removal_mode 0)
			)
			(polygon
				(pts
					(xy 22.4536 -61.468) (xy 23.0632 -61.468) (xy 23.0632 -61.6204) (xy 22.4536 -61.6204)
				)
			)
		)
		(zone
			(layer "B.Cu")
			(hatch none 0.5)
			(connect_pads
				(clearance 0)
			)
			(min_thickness 0.25)
			(keepout
				(tracks allowed)
				(vias not_allowed)
				(pads allowed)
				(copperpour not_allowed)
				(footprints allowed)
			)
			(placement
				(enabled no)
				(sheetname "")
			)
			(fill
				(thermal_gap 0.5)
				(thermal_bridge_width 0.5)
				(island_removal_mode 0)
			)
			(polygon
				(pts
					(xy 22.4536 -61.468) (xy 23.0632 -61.468) (xy 23.0632 -61.6204) (xy 22.4536 -61.6204)
				)
			)
		)
	)
	(footprint ""
		(layer "B.Cu")
		(at 88.519 -86.741 180)
		(property "Reference" "R203"
			(at -0.254 5.80263 0)
			(unlocked yes)
			(layer "B.SilkS")
			(effects
				(font
					(size 0.7874 0.5842)
					(thickness 0.1524)
				)
				(justify mirror)
			)
		)
		(property "Value" "VAL*"
			(at -0.02032 2.13233 180)
			(unlocked yes)
			(layer "B.Fab")
			(hide yes)
			(effects
				(font
					(size 0.7874 0.5842)
					(thickness 0.1524)
				)
				(justify mirror)
			)
		)
		(property "Tolerance" "TOL*"
			(at -0.044704 3.05435 180)
			(unlocked yes)
			(layer "Cmts.User")
			(hide yes)
			(effects
				(font
					(size 0.7874 0.5842)
					(thickness 0.1524)
				)
				(justify mirror)
			)
		)
		(property "User Part Number" "PARTNUM*"
			(at -0.02032 4.024884 180)
			(unlocked yes)
			(layer "Cmts.User")
			(hide yes)
			(effects
				(font
					(size 0.7874 0.5842)
					(thickness 0.1524)
				)
				(justify mirror)
			)
		)
		(property "Device Type" "RESISTOR-G155-133R0-01,33OHM,1%"
			(at -0.008382 1.210564 180)
			(unlocked yes)
			(layer "B.Fab")
			(hide yes)
			(effects
				(font
					(size 0.7874 0.5842)
					(thickness 0.1524)
				)
				(justify mirror)
			)
		)
		(duplicate_pad_numbers_are_jumpers no)
		(fp_line
			(start 1.143 0.5588)
			(end -1.143 0.5588)
			(stroke
				(width 0.1)
				(type default)
			)
			(layer "B.SilkS")
		)
		(fp_line
			(start 1.143 -0.5588)
			(end 1.143 0.5588)
			(stroke
				(width 0.1)
				(type default)
			)
			(layer "B.SilkS")
		)
		(fp_line
			(start -1.143 0.5588)
			(end -1.143 -0.5588)
			(stroke
				(width 0.1)
				(type default)
			)
			(layer "B.SilkS")
		)
		(fp_line
			(start -1.143 -0.5588)
			(end 1.143 -0.5588)
			(stroke
				(width 0.1)
				(type default)
			)
			(layer "B.SilkS")
		)
		(fp_rect
			(start 1.143 -0.5588)
			(end -1.143 0.5588)
			(stroke
				(width 0)
				(type default)
			)
			(fill no)
			(layer "B.CrtYd")
		)
		(fp_line
			(start 0.508 0.3048)
			(end -0.508 0.3048)
			(stroke
				(width 0.1)
				(type default)
			)
			(layer "B.Fab")
		)
		(fp_line
			(start 0.508 -0.3048)
			(end 0.508 0.3048)
			(stroke
				(width 0.1)
				(type default)
			)
			(layer "B.Fab")
		)
		(fp_line
			(start -0.508 0.3048)
			(end -0.508 -0.3048)
			(stroke
				(width 0.1)
				(type default)
			)
			(layer "B.Fab")
		)
		(fp_line
			(start -0.508 -0.3048)
			(end 0.508 -0.3048)
			(stroke
				(width 0.1)
				(type default)
			)
			(layer "B.Fab")
		)
		(pad "1" smd rect
			(at 0.5334 0)
			(size 0.7112 0.6096)
			(layers "B.Cu" "B.Mask" "B.Paste")
			(net "UNNAMED_127_MT25QL128ABA1ESESOP")
		)
		(pad "2" smd rect
			(at -0.5334 0)
			(size 0.7112 0.6096)
			(layers "B.Cu" "B.Mask" "B.Paste")
			(net "FLASH_DQ0_MOSI")
		)
		(zone
			(layer "B.Cu")
			(hatch none 0.5)
			(connect_pads
				(clearance 0)
			)
			(min_thickness 0.25)
			(keepout
				(tracks allowed)
				(vias not_allowed)
				(pads allowed)
				(copperpour not_allowed)
				(footprints allowed)
			)
			(placement
				(enabled no)
				(sheetname "")
			)
			(fill
				(thermal_gap 0.5)
				(thermal_bridge_width 0.5)
				(island_removal_mode 0)
			)
			(polygon
				(pts
					(xy 88.4428 -86.4362) (xy 88.5952 -86.4362) (xy 88.5952 -87.0458) (xy 88.4428 -87.0458)
				)
			)
		)
	)
	(footprint ""
		(layer "B.Cu")
		(at 147.955 -19.685 -90)
		(property "Reference" "C293"
			(at -2.794 0.03937 270)
			(unlocked yes)
			(layer "B.SilkS")
			(effects
				(font
					(size 0.7874 0.5842)
					(thickness 0.1524)
				)
				(justify mirror)
			)
		)
		(property "Value" "VAL*"
			(at -0.0762 2.067306 270)
			(unlocked yes)
			(layer "B.Fab")
			(hide yes)
			(effects
				(font
					(size 0.7874 0.5842)
					(thickness 0.1524)
				)
				(justify mirror)
			)
		)
		(property "Tolerance" "TOL*"
			(at -0.0762 3.032506 270)
			(unlocked yes)
			(layer "Cmts.User")
			(hide yes)
			(effects
				(font
					(size 0.7874 0.5842)
					(thickness 0.1524)
				)
				(justify mirror)
			)
		)
		(property "User Part Number" "PARTNUM*"
			(at -0.1016 4.023106 270)
			(unlocked yes)
			(layer "Cmts.User")
			(hide yes)
			(effects
				(font
					(size 0.7874 0.5842)
					(thickness 0.1524)
				)
				(justify mirror)
			)
		)
		(property "Device Type" "CAPACITOR-G105-0B224-DK,0.22UFA"
			(at -0.0508 1.127506 270)
			(unlocked yes)
			(layer "B.Fab")
			(hide yes)
			(effects
				(font
					(size 0.7874 0.5842)
					(thickness 0.1524)
				)
				(justify mirror)
			)
		)
		(duplicate_pad_numbers_are_jumpers no)
		(fp_line
			(start -1.143 0.5588)
			(end -1.143 -0.5588)
			(stroke
				(width 0.1)
				(type default)
			)
			(layer "B.SilkS")
		)
		(fp_line
			(start 1.143 0.5588)
			(end -1.143 0.5588)
			(stroke
				(width 0.1)
				(type default)
			)
			(layer "B.SilkS")
		)
		(fp_line
			(start -1.143 -0.5588)
			(end 1.143 -0.5588)
			(stroke
				(width 0.1)
				(type default)
			)
			(layer "B.SilkS")
		)
		(fp_line
			(start 1.143 -0.5588)
			(end 1.143 0.5588)
			(stroke
				(width 0.1)
				(type default)
			)
			(layer "B.SilkS")
		)
		(fp_rect
			(start -1.143 0.5588)
			(end 1.143 -0.5588)
			(stroke
				(width 0)
				(type default)
			)
			(fill no)
			(layer "B.CrtYd")
		)
		(fp_line
			(start -0.508 0.3048)
			(end -0.508 -0.3048)
			(stroke
				(width 0.1)
				(type default)
			)
			(layer "B.Fab")
		)
		(fp_line
			(start 0.508 0.3048)
			(end -0.508 0.3048)
			(stroke
				(width 0.1)
				(type default)
			)
			(layer "B.Fab")
		)
		(fp_line
			(start -0.508 -0.3048)
			(end 0.508 -0.3048)
			(stroke
				(width 0.1)
				(type default)
			)
			(layer "B.Fab")
		)
		(fp_line
			(start 0.508 -0.3048)
			(end 0.508 0.3048)
			(stroke
				(width 0.1)
				(type default)
			)
			(layer "B.Fab")
		)
		(pad "1" smd rect
			(at 0.5334 0 90)
			(size 0.7112 0.6096)
			(layers "B.Cu" "B.Mask" "B.Paste")
			(net "UNNAMED_515_CAPACITOR_I128_1")
		)
		(pad "2" smd rect
			(at -0.5334 0 90)
			(size 0.7112 0.6096)
			(layers "B.Cu" "B.Mask" "B.Paste")
			(net "SG")
		)
		(zone
			(layer "B.Cu")
			(hatch none 0.5)
			(connect_pads
				(clearance 0)
			)
			(min_thickness 0.25)
			(keepout
				(tracks allowed)
				(vias not_allowed)
				(pads allowed)
				(copperpour not_allowed)
				(footprints allowed)
			)
			(placement
				(enabled no)
				(sheetname "")
			)
			(fill
				(thermal_gap 0.5)
				(thermal_bridge_width 0.5)
				(island_removal_mode 0)
			)
			(polygon
				(pts
					(xy 147.6502 -19.7612) (xy 147.6502 -19.6088) (xy 148.2598 -19.6088) (xy 148.2598 -19.7612)
				)
			)
		)
		(zone
			(layer "B.Cu")
			(hatch none 0.5)
			(connect_pads
				(clearance 0)
			)
			(min_thickness 0.25)
			(keepout
				(tracks not_allowed)
				(vias allowed)
				(pads allowed)
				(copperpour not_allowed)
				(footprints allowed)
			)
			(placement
				(enabled no)
				(sheetname "")
			)
			(fill
				(thermal_gap 0.5)
				(thermal_bridge_width 0.5)
				(island_removal_mode 0)
			)
			(polygon
				(pts
					(xy 147.6502 -19.7612) (xy 147.6502 -19.6088) (xy 148.2598 -19.6088) (xy 148.2598 -19.7612)
				)
			)
		)
	)
	(footprint ""
		(layer "B.Cu")
		(at 156.718 -42.037 -90)
		(property "Reference" "R429"
			(at 8.29437 0.635 0)
			(unlocked yes)
			(layer "B.SilkS")
			(effects
				(font
					(size 0.7874 0.5842)
					(thickness 0.1524)
				)
				(justify mirror)
			)
		)
		(property "Value" "VAL*"
			(at -0.02032 2.13233 270)
			(unlocked yes)
			(layer "B.Fab")
			(hide yes)
			(effects
				(font
					(size 0.7874 0.5842)
					(thickness 0.1524)
				)
				(justify mirror)
			)
		)
		(property "Tolerance" "TOL*"
			(at -0.044704 3.05435 270)
			(unlocked yes)
			(layer "Cmts.User")
			(hide yes)
			(effects
				(font
					(size 0.7874 0.5842)
					(thickness 0.1524)
				)
				(justify mirror)
			)
		)
		(property "User Part Number" "PARTNUM*"
			(at -0.02032 4.024884 270)
			(unlocked yes)
			(layer "Cmts.User")
			(hide yes)
			(effects
				(font
					(size 0.7874 0.5842)
					(thickness 0.1524)
				)
				(justify mirror)
			)
		)
		(property "Device Type" "RESISTOR-G155-133R0-01,33OHM,1%"
			(at -0.008382 1.210564 270)
			(unlocked yes)
			(layer "B.Fab")
			(hide yes)
			(effects
				(font
					(size 0.7874 0.5842)
					(thickness 0.1524)
				)
				(justify mirror)
			)
		)
		(duplicate_pad_numbers_are_jumpers no)
		(fp_line
			(start -1.143 0.5588)
			(end -1.143 -0.5588)
			(stroke
				(width 0.1)
				(type default)
			)
			(layer "B.SilkS")
		)
		(fp_line
			(start 1.143 0.5588)
			(end -1.143 0.5588)
			(stroke
				(width 0.1)
				(type default)
			)
			(layer "B.SilkS")
		)
		(fp_line
			(start -1.143 -0.5588)
			(end 1.143 -0.5588)
			(stroke
				(width 0.1)
				(type default)
			)
			(layer "B.SilkS")
		)
		(fp_line
			(start 1.143 -0.5588)
			(end 1.143 0.5588)
			(stroke
				(width 0.1)
				(type default)
			)
			(layer "B.SilkS")
		)
		(fp_poly
			(pts
				(xy 1.143 0.5588) (xy -1.143 0.5588) (xy -1.143 -0.5588) (xy 1.143 -0.5588)
			)
			(stroke
				(width 0)
				(type default)
			)
			(fill no)
			(layer "B.CrtYd")
		)
		(fp_line
			(start -0.508 0.3048)
			(end -0.508 -0.3048)
			(stroke
				(width 0.1)
				(type default)
			)
			(layer "B.Fab")
		)
		(fp_line
			(start 0.508 0.3048)
			(end -0.508 0.3048)
			(stroke
				(width 0.1)
				(type default)
			)
			(layer "B.Fab")
		)
		(fp_line
			(start -0.508 -0.3048)
			(end 0.508 -0.3048)
			(stroke
				(width 0.1)
				(type default)
			)
			(layer "B.Fab")
		)
		(fp_line
			(start 0.508 -0.3048)
			(end 0.508 0.3048)
			(stroke
				(width 0.1)
				(type default)
			)
			(layer "B.Fab")
		)
		(pad "1" smd rect
			(at 0.5334 0 90)
			(size 0.7112 0.6096)
			(layers "B.Cu" "B.Mask" "B.Paste")
			(net "FPGA_IO_5")
		)
		(pad "2" smd rect
			(at -0.5334 0 90)
			(size 0.7112 0.6096)
			(layers "B.Cu" "B.Mask" "B.Paste")
			(net "UNNAMED_16_CONNHDR2X6FSSMT_I1_2")
		)
		(zone
			(layer "B.Cu")
			(hatch none 0.5)
			(connect_pads
				(clearance 0)
			)
			(min_thickness 0.25)
			(keepout
				(tracks allowed)
				(vias not_allowed)
				(pads allowed)
				(copperpour not_allowed)
				(footprints allowed)
			)
			(placement
				(enabled no)
				(sheetname "")
			)
			(fill
				(thermal_gap 0.5)
				(thermal_bridge_width 0.5)
				(island_removal_mode 0)
			)
			(polygon
				(pts
					(xy 156.4132 -41.9608) (xy 157.0228 -41.9608) (xy 157.0228 -42.1132) (xy 156.4132 -42.1132)
				)
			)
		)
		(zone
			(layer "B.Cu")
			(hatch none 0.5)
			(connect_pads
				(clearance 0)
			)
			(min_thickness 0.25)
			(keepout
				(tracks not_allowed)
				(vias allowed)
				(pads allowed)
				(copperpour not_allowed)
				(footprints allowed)
			)
			(placement
				(enabled no)
				(sheetname "")
			)
			(fill
				(thermal_gap 0.5)
				(thermal_bridge_width 0.5)
				(island_removal_mode 0)
			)
			(polygon
				(pts
					(xy 156.4132 -41.9608) (xy 157.0228 -41.9608) (xy 157.0228 -42.1132) (xy 156.4132 -42.1132)
				)
			)
		)
	)
)
